# T6G (Grand Teton) — schematic parts with pin connectivity, parts 8081–8081 of 8303; source: Cadence DE-HDL packaged netlist (pstxprt.dat, pstxnet.dat, pstchip.dat)

U25  GENOA_SP5  SOCKET6096_13568-001 IO  pkg SOCKET6096_93-4X120-45XA  page 10  (pins 3361-3696 of 6096)
  CH57  VSS_CH57  POWER  = GND
  CH58  MDB_DATA7  BI  = M_D_CPU0_SB_DQ<7>
  CH59  VSS_CH59  POWER  = GND
  CH60  MDB_DATA8  BI  = M_D_CPU0_SB_DQ<8>
  CH61  VSS_CH61  POWER  = GND
  CH62  MBB_DATA7  BI  = M_B_CPU0_SB_DQ<7>
  CH63  MBB_DATA8  BI  = M_B_CPU0_SB_DQ<8>
  CH64  VSS_CH64  POWER  = GND
  CH65  MFB_DATA7  BI  = M_F_CPU0_SB_DQ<7>
  CH66  VSS_CH66  POWER  = GND
  CH67  MFB_DATA8  BI  = M_F_CPU0_SB_DQ<8>
  CH68  VSS_CH68  POWER  = GND
  CH69  MEB_DATA7  BI  = M_E_CPU0_SB_DQ<7>
  CH70  MEB_DATA8  BI  = M_E_CPU0_SB_DQ<8>
  CH71  VSS_CH71  POWER  = GND
  CH72  MAB_DATA7  BI  = M_A_CPU0_SB_DQ<7>
  CH73  VSS_CH73  POWER  = GND
  CH74  MAB_DATA8  BI  = M_A_CPU0_SB_DQ<8>
  CJ1  VSS_CJ1  POWER  = GND
  CJ2  MGB_DATA10  BI  = M_G_CPU0_SB_DQ<10>
  CJ3  MGB_DATA9  BI  = M_G_CPU0_SB_DQ<9>
  CJ4  VSS_CJ4  POWER  = GND
  CJ5  MKB_DATA10  BI  = M_K_CPU0_SB_DQ<10>
  CJ6  VSS_CJ6  POWER  = GND
  CJ7  MKB_DATA9  BI  = M_K_CPU0_SB_DQ<9>
  CJ8  VSS_CJ8  POWER  = GND
  CJ9  MLB_DATA10  BI  = M_L_CPU0_SB_DQ<10>
  CJ10  MLB_DATA9  BI  = M_L_CPU0_SB_DQ<9>
  CJ11  VSS_CJ11  POWER  = GND
  CJ12  MHB_DATA10  BI  = M_H_CPU0_SB_DQ<10>
  CJ13  VSS_CJ13  POWER  = GND
  CJ14  MHB_DATA9  BI  = M_H_CPU0_SB_DQ<9>
  CJ15  VSS_CJ15  POWER  = GND
  CJ16  MJB_DATA10  BI  = M_J_CPU0_SB_DQ<10>
  CJ17  MJB_DATA9  BI  = M_J_CPU0_SB_DQ<9>
  CJ18  VSS_CJ18  POWER  = GND
  CJ19  MIB_DATA10  BI  = M_I_CPU0_SB_DQ<10>
  CJ20  VSS_CJ20  POWER  = GND
  CJ21  MIB_DATA9  BI  = M_I_CPU0_SB_DQ<9>
  CJ22  VDD_11_S3_CJ22  POWER  = PVDD11_S3_P0
  CJ23  VSS_CJ23  POWER  = GND
  CJ24  TEST47_CCD1  TRI  = TP_CPU0_TEST47_CCD1
  CJ25  TEST5_CCD5  TRI  = TP_CPU0_TEST5_CCD5
  CJ26  TEST4_CCD5  TRI  = TP_CPU0_TEST4_CCD5
  CJ27  TEST5_CCD1  TRI  = TP_CPU0_TEST5_CCD1
  CJ28  TEST4_CCD1  TRI  = TP_CPU0_TEST4_CCD1
  CJ29  TEST6_X3D1  OUT  = TP_CPU0_TEST6_X3D1
  CJ30  TEST6_CCD1  OUT  = TP_CPU0_TEST6_CCD1
  CJ31  VSS_CJ31  POWER  = GND
  CJ32  P3_TXN4  OUT  = P5E_CPU0_P3_TX_DN<4>
  CJ33  P3_TXP4  OUT  = P5E_CPU0_P3_TX_DP<4>
  CJ34  VSS_CJ34  POWER  = GND
  CJ35  VSS_CJ35  POWER  = GND
  CJ36  VSS_CJ36  POWER  = GND
  CJ40  VSS_CJ40  POWER  = GND
  CJ41  VSS_CJ41  POWER  = GND
  CJ42  VSS_CJ42  POWER  = GND
  CJ43  P1_RXP11  IN  = P5E_CPU0_P1_RX_DP<11>
  CJ44  P1_RXN11  IN  = P5E_CPU0_P1_RX_DN<11>
  CJ45  VSS_CJ45  POWER  = GND
  CJ46  TEST6_CCD2  OUT  = TP_CPU0_TEST6_CCD2
  CJ47  TEST4_CCD10  TRI  = TP_CPU0_TEST4_CCD10
  CJ48  TEST4_CCD2  TRI  = TP_CPU0_TEST4_CCD2
  CJ49  TEST5_CCD2  TRI  = TP_CPU0_TEST5_CCD2
  CJ50  TEST4_CCD6  TRI  = TP_CPU0_TEST4_CCD6
  CJ51  TEST5_CCD6  TRI  = TP_CPU0_TEST5_CCD6
  CJ52  TEST6_X3D3  OUT  = TP_CPU0_TEST6_X3D3
  CJ53  TEST6_X3D5  OUT  = TP_CPU0_TEST6_X3D5
  CJ54  VDDIO_CJ54  POWER  = PVDDIO_P0
  CJ55  MCB_DATA9  BI  = M_C_CPU0_SB_DQ<9>
  CJ56  VSS_CJ56  POWER  = GND
  CJ57  MCB_DATA10  BI  = M_C_CPU0_SB_DQ<10>
  CJ58  VSS_CJ58  POWER  = GND
  CJ59  MDB_DATA9  BI  = M_D_CPU0_SB_DQ<9>
  CJ60  MDB_DATA10  BI  = M_D_CPU0_SB_DQ<10>
  CJ61  VSS_CJ61  POWER  = GND
  CJ62  MBB_DATA9  BI  = M_B_CPU0_SB_DQ<9>
  CJ63  VSS_CJ63  POWER  = GND
  CJ64  MBB_DATA10  BI  = M_B_CPU0_SB_DQ<10>
  CJ65  VSS_CJ65  POWER  = GND
  CJ66  MFB_DATA9  BI  = M_F_CPU0_SB_DQ<9>
  CJ67  MFB_DATA10  BI  = M_F_CPU0_SB_DQ<10>
  CJ68  VSS_CJ68  POWER  = GND
  CJ69  MEB_DATA9  BI  = M_E_CPU0_SB_DQ<9>
  CJ70  VSS_CJ70  POWER  = GND
  CJ71  MEB_DATA10  BI  = M_E_CPU0_SB_DQ<10>
  CJ72  VSS_CJ72  POWER  = GND
  CJ73  MAB_DATA9  BI  = M_A_CPU0_SB_DQ<9>
  CJ74  MAB_DATA10  BI  = M_A_CPU0_SB_DQ<10>
  CJ75  VSS_CJ75  POWER  = GND
  CK2  MGB_DQS_H1  BI  = M_G_CPU0_SB_DQS_DP<1>
  CK3  VSS_CK3  POWER  = GND
  CK4  MGB_DATA11  BI  = M_G_CPU0_SB_DQ<11>
  CK5  VDD_11_S3_CK5  POWER  = PVDD11_S3_P0
  CK6  MKB_DQS_H1  BI  = M_K_CPU0_SB_DQS_DP<1>
  CK7  MKB_DATA11  BI  = M_K_CPU0_SB_DQ<11>
  CK8  VSS_CK8  POWER  = GND
  CK9  MLB_DQS_H1  BI  = M_L_CPU0_SB_DQS_DP<1>
  CK10  VSS_CK10  POWER  = GND
  CK11  MLB_DATA11  BI  = M_L_CPU0_SB_DQ<11>
  CK12  VDD_11_S3_CK12  POWER  = PVDD11_S3_P0
  CK13  MHB_DQS_H1  BI  = M_H_CPU0_SB_DQS_DP<1>
  CK14  MHB_DATA11  BI  = M_H_CPU0_SB_DQ<11>
  CK15  VSS_CK15  POWER  = GND
  CK16  MJB_DQS_H1  BI  = M_J_CPU0_SB_DQS_DP<1>
  CK17  VSS_CK17  POWER  = GND
  CK18  MJB_DATA11  BI  = M_J_CPU0_SB_DQ<11>
  CK19  VDD_11_S3_CK19  POWER  = PVDD11_S3_P0
  CK20  MIB_DQS_H1  BI  = M_I_CPU0_SB_DQS_DP<1>
  CK21  MIB_DATA11  BI  = M_I_CPU0_SB_DQ<11>
  CK22  VSS_CK22  POWER  = GND
  CK23  VSS_CK23  POWER  = GND
  CK24  VSS_CK24  POWER  = GND
  CK25  VSS_CK25  POWER  = GND
  CK26  VSS_CK26  POWER  = GND
  CK27  VSS_CK27  POWER  = GND
  CK28  VSS_CK28  POWER  = GND
  CK29  TEST5_CCD9  TRI  = TP_CPU0_TEST5_CCD9
  CK30  TEST4_CCD9  TRI  = TP_CPU0_TEST4_CCD9
  CK31  VSS_CK31  POWER  = GND
  CK32  VSS_CK32  POWER  = GND
  CK33  VSS_CK33  POWER  = GND
  CK34  VSS_CK34  POWER  = GND
  CK35  VDDCR_CPU1_CK35  POWER  = PVDDCR_CPU1_P0
  CK36  VDDCR_CPU1_CK36  POWER  = PVDDCR_CPU1_P0
  CK37  VSS_CK37  POWER  = GND
  CK39  VSS_CK39  POWER  = GND
  CK40  VDDCR_CPU1_CK40  POWER  = PVDDCR_CPU1_P0
  CK41  VDDCR_CPU1_CK41  POWER  = PVDDCR_CPU1_P0
  CK42  VSS_CK42  POWER  = GND
  CK43  VSS_CK43  POWER  = GND
  CK44  VSS_CK44  POWER  = GND
  CK45  VSS_CK45  POWER  = GND
  CK46  TEST47_CCD2  TRI  = TP_CPU0_TEST47_CCD2
  CK47  TEST5_CCD10  TRI  = TP_CPU0_TEST5_CCD10
  CK48  VSS_CK48  POWER  = GND
  CK49  VSS_CK49  POWER  = GND
  CK50  VSS_CK50  POWER  = GND
  CK51  VSS_CK51  POWER  = GND
  CK52  VSS_CK52  POWER  = GND
  CK53  VSS_CK53  POWER  = GND
  CK54  VSS_CK54  POWER  = GND
  CK55  MCB_DATA11  BI  = M_C_CPU0_SB_DQ<11>
  CK56  MCB_DQS_H1  BI  = M_C_CPU0_SB_DQS_DP<1>
  CK57  VDDIO_CK57  POWER  = PVDDIO_P0
  CK58  MDB_DATA11  BI  = M_D_CPU0_SB_DQ<11>
  CK59  VSS_CK59  POWER  = GND
  CK60  MDB_DQS_H1  BI  = M_D_CPU0_SB_DQS_DP<1>
  CK61  VSS_CK61  POWER  = GND
  CK62  MBB_DATA11  BI  = M_B_CPU0_SB_DQ<11>
  CK63  MBB_DQS_H1  BI  = M_B_CPU0_SB_DQS_DP<1>
  CK64  VDDIO_CK64  POWER  = PVDDIO_P0
  CK65  MFB_DATA11  BI  = M_F_CPU0_SB_DQ<11>
  CK66  VSS_CK66  POWER  = GND
  CK67  MFB_DQS_H1  BI  = M_F_CPU0_SB_DQS_DP<1>
  CK68  VSS_CK68  POWER  = GND
  CK69  MEB_DATA11  BI  = M_E_CPU0_SB_DQ<11>
  CK70  MEB_DQS_H1  BI  = M_E_CPU0_SB_DQS_DP<1>
  CK71  VDDIO_CK71  POWER  = PVDDIO_P0
  CK72  MAB_DATA11  BI  = M_A_CPU0_SB_DQ<11>
  CK73  VSS_CK73  POWER  = GND
  CK74  MAB_DQS_H1  BI  = M_A_CPU0_SB_DQS_DP<1>
  CL1  VSS_CL1  POWER  = GND
  CL2  MGB_DQS_L1  BI  = M_G_CPU0_SB_DQS_DN<1>
  CL3  MGB_DQS_L6  BI  = M_G_CPU0_SB_DQS_DN<6>
  CL4  VSS_CL4  POWER  = GND
  CL5  MKB_DQS_L1  BI  = M_K_CPU0_SB_DQS_DN<1>
  CL6  VSS_CL6  POWER  = GND
  CL7  MKB_DQS_L6  BI  = M_K_CPU0_SB_DQS_DN<6>
  CL8  VSS_CL8  POWER  = GND
  CL9  MLB_DQS_L1  BI  = M_L_CPU0_SB_DQS_DN<1>
  CL10  MLB_DQS_L6  BI  = M_L_CPU0_SB_DQS_DN<6>
  CL11  VSS_CL11  POWER  = GND
  CL12  MHB_DQS_L1  BI  = M_H_CPU0_SB_DQS_DN<1>
  CL13  VSS_CL13  POWER  = GND
  CL14  MHB_DQS_L6  BI  = M_H_CPU0_SB_DQS_DN<6>
  CL15  VSS_CL15  POWER  = GND
  CL16  MJB_DQS_L1  BI  = M_J_CPU0_SB_DQS_DN<1>
  CL17  MJB_DQS_L6  BI  = M_J_CPU0_SB_DQS_DN<6>
  CL18  VSS_CL18  POWER  = GND
  CL19  MIB_DQS_L1  BI  = M_I_CPU0_SB_DQS_DN<1>
  CL20  VSS_CL20  POWER  = GND
  CL21  MIB_DQS_L6  BI  = M_I_CPU0_SB_DQS_DN<6>
  CL22  VSS_CL22  POWER  = GND
  CL23  P2_RXP13  IN  = P5E_CPU0_P2_RX_DP<13>
  CL24  P2_RXN13  IN  = P5E_CPU0_P2_RX_DN<13>
  CL25  VSS_CL25  POWER  = GND
  CL26  P2_RXP9  IN  = P5E_CPU0_P2_RX_DP<9>
  CL27  P2_RXN9  IN  = P5E_CPU0_P2_RX_DN<9>
  CL28  VSS_CL28  POWER  = GND
  CL29  VDDCR_CPU1_CL29  POWER  = PVDDCR_CPU1_P0
  CL30  VDDCR_CPU1_CL30  POWER  = PVDDCR_CPU1_P0
  CL31  VSS_CL31  POWER  = GND
  CL32  VDDCR_CPU1_CL32  POWER  = PVDDCR_CPU1_P0
  CL33  VDDCR_CPU1_CL33  POWER  = PVDDCR_CPU1_P0
  CL34  VSS_CL34  POWER  = GND
  CL35  VSS_CL35  POWER  = GND
  CL36  VSS_CL36  POWER  = GND
  CL40  VSS_CL40  POWER  = GND
  CL41  VSS_CL41  POWER  = GND
  CL42  VSS_CL42  POWER  = GND
  CL43  VDDCR_CPU1_CL43  POWER  = PVDDCR_CPU1_P0
  CL44  VDDCR_CPU1_CL44  POWER  = PVDDCR_CPU1_P0
  CL45  VSS_CL45  POWER  = GND
  CL46  VDDCR_CPU1_CL46  POWER  = PVDDCR_CPU1_P0
  CL47  VDDCR_CPU1_CL47  POWER  = PVDDCR_CPU1_P0
  CL48  VSS_CL48  POWER  = GND
  CL49  \p0_txn6||sata06_txn\  OUT  = P5E_CPU0_P0_TX_DN<6>
  CL50  \p0_txp6||sata06_txp\  OUT  = P5E_CPU0_P0_TX_DP<6>
  CL51  VSS_CL51  POWER  = GND
  CL52  \p0_txn2||sata02_txn\  OUT  = P5E_CPU0_P0_TX_DN<2>
  CL53  \p0_txp2||sata02_txp\  OUT  = P5E_CPU0_P0_TX_DP<2>
  CL54  VSS_CL54  POWER  = GND
  CL55  MCB_DQS_L6  BI  = M_C_CPU0_SB_DQS_DN<6>
  CL56  VSS_CL56  POWER  = GND
  CL57  MCB_DQS_L1  BI  = M_C_CPU0_SB_DQS_DN<1>
  CL58  VSS_CL58  POWER  = GND
  CL59  MDB_DQS_L6  BI  = M_D_CPU0_SB_DQS_DN<6>
  CL60  MDB_DQS_L1  BI  = M_D_CPU0_SB_DQS_DN<1>
  CL61  VSS_CL61  POWER  = GND
  CL62  MBB_DQS_L6  BI  = M_B_CPU0_SB_DQS_DN<6>
  CL63  VSS_CL63  POWER  = GND
  CL64  MBB_DQS_L1  BI  = M_B_CPU0_SB_DQS_DN<1>
  CL65  VSS_CL65  POWER  = GND
  CL66  MFB_DQS_L6  BI  = M_F_CPU0_SB_DQS_DN<6>
  CL67  MFB_DQS_L1  BI  = M_F_CPU0_SB_DQS_DN<1>
  CL68  VSS_CL68  POWER  = GND
  CL69  MEB_DQS_L6  BI  = M_E_CPU0_SB_DQS_DN<6>
  CL70  VSS_CL70  POWER  = GND
  CL71  MEB_DQS_L1  BI  = M_E_CPU0_SB_DQS_DN<1>
  CL72  VSS_CL72  POWER  = GND
  CL73  MAB_DQS_L6  BI  = M_A_CPU0_SB_DQS_DN<6>
  CL74  MAB_DQS_L1  BI  = M_A_CPU0_SB_DQS_DN<1>
  CL75  VSS_CL75  POWER  = GND
  CM2  MGB_DATA12  BI  = M_G_CPU0_SB_DQ<12>
  CM3  VSS_CM3  POWER  = GND
  CM4  MGB_DQS_H6  BI  = M_G_CPU0_SB_DQS_DP<6>
  CM5  VSS_CM5  POWER  = GND
  CM6  MKB_DATA12  BI  = M_K_CPU0_SB_DQ<12>
  CM7  MKB_DQS_H6  BI  = M_K_CPU0_SB_DQS_DP<6>
  CM8  VSS_CM8  POWER  = GND
  CM9  MLB_DATA12  BI  = M_L_CPU0_SB_DQ<12>
  CM10  VSS_CM10  POWER  = GND
  CM11  MLB_DQS_H6  BI  = M_L_CPU0_SB_DQS_DP<6>
  CM12  VSS_CM12  POWER  = GND
  CM13  MHB_DATA12  BI  = M_H_CPU0_SB_DQ<12>
  CM14  MHB_DQS_H6  BI  = M_H_CPU0_SB_DQS_DP<6>
  CM15  VSS_CM15  POWER  = GND
  CM16  MJB_DATA12  BI  = M_J_CPU0_SB_DQ<12>
  CM17  VSS_CM17  POWER  = GND
  CM18  MJB_DQS_H6  BI  = M_J_CPU0_SB_DQS_DP<6>
  CM19  VSS_CM19  POWER  = GND
  CM20  MIB_DATA12  BI  = M_I_CPU0_SB_DQ<12>
  CM21  MIB_DQS_H6  BI  = M_I_CPU0_SB_DQS_DP<6>
  CM22  VDD_11_S3_CM22  POWER  = PVDD11_S3_P0
  CM23  VSS_CM23  POWER  = GND
  CM24  VSS_CM24  POWER  = GND
  CM25  VSS_CM25  POWER  = GND
  CM26  VSS_CM26  POWER  = GND
  CM27  VSS_CM27  POWER  = GND
  CM28  VSS_CM28  POWER  = GND
  CM29  VSS_CM29  POWER  = GND
  CM30  VSS_CM30  POWER  = GND
  CM31  VSS_CM31  POWER  = GND
  CM32  VSS_CM32  POWER  = GND
  CM33  VSS_CM33  POWER  = GND
  CM34  VSS_CM34  POWER  = GND
  CM35  P2_RXP0  IN  = P5E_CPU0_P2_RX_DP<0>
  CM36  P2_RXN0  IN  = P5E_CPU0_P2_RX_DN<0>
  CM37  VSS_CM37  POWER  = GND
  CM39  VSS_CM39  POWER  = GND
  CM40  \p0_txn15||sata17_txn\  OUT  = P5E_CPU0_P0_TX_DN<15>
  CM41  \p0_txp15||sata17_txp\  OUT  = P5E_CPU0_P0_TX_DP<15>
  CM42  VSS_CM42  POWER  = GND
  CM43  VSS_CM43  POWER  = GND
  CM44  VSS_CM44  POWER  = GND
  CM45  VSS_CM45  POWER  = GND
  CM46  VSS_CM46  POWER  = GND
  CM47  VSS_CM47  POWER  = GND
  CM48  VSS_CM48  POWER  = GND
  CM49  VSS_CM49  POWER  = GND
  CM50  VSS_CM50  POWER  = GND
  CM51  VSS_CM51  POWER  = GND
  CM52  VSS_CM52  POWER  = GND
  CM53  VSS_CM53  POWER  = GND
  CM54  VDDIO_CM54  POWER  = PVDDIO_P0
  CM55  MCB_DQS_H6  BI  = M_C_CPU0_SB_DQS_DP<6>
  CM56  MCB_DATA12  BI  = M_C_CPU0_SB_DQ<12>
  CM57  VSS_CM57  POWER  = GND
  CM58  MDB_DQS_H6  BI  = M_D_CPU0_SB_DQS_DP<6>
  CM59  VSS_CM59  POWER  = GND
  CM60  MDB_DATA12  BI  = M_D_CPU0_SB_DQ<12>
  CM61  VSS_CM61  POWER  = GND
  CM62  MBB_DQS_H6  BI  = M_B_CPU0_SB_DQS_DP<6>
  CM63  MBB_DATA12  BI  = M_B_CPU0_SB_DQ<12>
  CM64  VSS_CM64  POWER  = GND
  CM65  MFB_DQS_H6  BI  = M_F_CPU0_SB_DQS_DP<6>
  CM66  VSS_CM66  POWER  = GND
  CM67  MFB_DATA12  BI  = M_F_CPU0_SB_DQ<12>
  CM68  VSS_CM68  POWER  = GND
  CM69  MEB_DQS_H6  BI  = M_E_CPU0_SB_DQS_DP<6>
  CM70  MEB_DATA12  BI  = M_E_CPU0_SB_DQ<12>
  CM71  VSS_CM71  POWER  = GND
  CM72  MAB_DQS_H6  BI  = M_A_CPU0_SB_DQS_DP<6>
  CM73  VSS_CM73  POWER  = GND
  CM74  MAB_DATA12  BI  = M_A_CPU0_SB_DQ<12>
  CN1  VSS_CN1  POWER  = GND
  CN2  MGB_DATA14  BI  = M_G_CPU0_SB_DQ<14>
  CN3  MGB_DATA13  BI  = M_G_CPU0_SB_DQ<13>
  CN4  VDD_11_S3_CN4  POWER  = PVDD11_S3_P0
  CN5  MKB_DATA14  BI  = M_K_CPU0_SB_DQ<14>
  CN6  VSS_CN6  POWER  = GND
  CN7  MKB_DATA13  BI  = M_K_CPU0_SB_DQ<13>
  CN8  VSS_CN8  POWER  = GND
  CN9  MLB_DATA14  BI  = M_L_CPU0_SB_DQ<14>
  CN10  MLB_DATA13  BI  = M_L_CPU0_SB_DQ<13>
  CN11  VDD_11_S3_CN11  POWER  = PVDD11_S3_P0
  CN12  MHB_DATA14  BI  = M_H_CPU0_SB_DQ<14>
  CN13  VSS_CN13  POWER  = GND
  CN14  MHB_DATA13  BI  = M_H_CPU0_SB_DQ<13>
  CN15  VSS_CN15  POWER  = GND
  CN16  MJB_DATA14  BI  = M_J_CPU0_SB_DQ<14>
  CN17  MJB_DATA13  BI  = M_J_CPU0_SB_DQ<13>
  CN18  VDD_11_S3_CN18  POWER  = PVDD11_S3_P0
  CN19  MIB_DATA14  BI  = M_I_CPU0_SB_DQ<14>
  CN20  VSS_CN20  POWER  = GND
  CN21  MIB_DATA13  BI  = M_I_CPU0_SB_DQ<13>
  CN22  VSS_CN22  POWER  = GND
  CN23  P2_RXP15  IN  = P5E_CPU0_P2_RX_DP<15>
  CN24  P2_RXN15  IN  = P5E_CPU0_P2_RX_DN<15>
  CN25  VSS_CN25  POWER  = GND
  CN26  P2_RXP12  IN  = P5E_CPU0_P2_RX_DP<12>
  CN27  P2_RXN12  IN  = P5E_CPU0_P2_RX_DN<12>
  CN28  VSS_CN28  POWER  = GND
  CN29  P2_RXP6  IN  = P5E_CPU0_P2_RX_DP<6>
  CN30  P2_RXN6  IN  = P5E_CPU0_P2_RX_DN<6>
